# BASEBOARD_FAB2 (Tioga Pass) — schematic netlist excerpt (pin names and nets, part order shuffled) for the footprints in the layout excerpt that follows; sources: Cadence DE-HDL packaged netlist, KiCad conversion of Wiwynn_Tioga_Pass_MB.brd

R1W26  RES  10.0K 1% EMPTY  pkg 0402  page 190 : A = RST_RSMRST_R_N ; B = GND
C1R21  CAP_A  0.1UF 16V 10% X7R  pkg 0402V  page 139 : A = P3V3_STBY ; B = GND
C7W12  SC22U16V5MX-4-GP  20%  pkg SMD-BCG5  page 220 : \1\ = VR_FET_SW_P12V_STBY_PVDDQ_DEF ; \2\ = GND

(kicad_pcb
	(version 20260206)
	(generator "pcbnew")
	(generator_version "10.0")
	(general
		(thickness 1.6)
		(legacy_teardrops no)
	)
	(paper "A4")
	(title_block
		(title "Wiwynn_Tioga_Pass_MB.brd")
		(comment 1 "Tioga Pass / footprints 4367-4369 of 4770")
	)
	(layers
		(0 "F.Cu" signal "TOP")
		(4 "In1.Cu" signal "L2GND")
		(6 "In2.Cu" signal "L3")
		(8 "In3.Cu" signal "L4GND")
		(10 "In4.Cu" signal "L5")
		(12 "In5.Cu" signal "L6GND")
		(14 "In6.Cu" signal "L7VCC")
		(16 "In7.Cu" signal "L8VCC")
		(18 "In8.Cu" signal "L9GND")
		(20 "In9.Cu" signal "L10")
		(22 "In10.Cu" signal "L11GND")
		(24 "In11.Cu" signal "L12")
		(26 "In12.Cu" signal "L13GND")
		(2 "B.Cu" signal "BOTTOM")
		(9 "F.Adhes" user "F.Adhesive")
		(11 "B.Adhes" user "B.Adhesive")
		(13 "F.Paste" user "Package Geometry/Pastemask Top")
		(15 "B.Paste" user "Package Geometry/Pastemask Bottom")
		(5 "F.SilkS" user "Ref Des/Silkscreen Top")
		(7 "B.SilkS" user "Ref Des/Silkscreen Bottom")
		(1 "F.Mask" user "Board Geometry/Soldermask Top")
		(3 "B.Mask" user "Board Geometry/Soldermask Bottom")
		(17 "Dwgs.User" user "User.Drawings")
		(19 "Cmts.User" user "User.Comments")
		(21 "Eco1.User" user "User.Eco1")
		(23 "Eco2.User" user "User.Eco2")
		(25 "Edge.Cuts" user "Board Geometry/Outline")
		(27 "Margin" user)
		(31 "F.CrtYd" user "Package Geometry/Place Bound Top")
		(29 "B.CrtYd" user "Package Geometry/Place Bound Bottom")
		(35 "F.Fab" user "Ref Des/Assembly Top")
		(33 "B.Fab" user "Ref Des/Assembly Bottom")
	)
	(footprint ""
		(layer "B.Cu")
		(at 377.75642 -67.2211)
		(property "Reference" "R1W26"
			(at 0.8382 -0.67818 0)
			(unlocked yes)
			(layer "B.SilkS")
			(effects
				(font
					(size 0.4064 0.254)
					(thickness 0.1524)
				)
				(justify left mirror)
			)
		)
		(property "Value" ""
			(at 0 0 0)
			(layer "B.Fab")
			(effects
				(font
					(size 1.27 1.27)
				)
				(justify mirror)
			)
		)
		(duplicate_pad_numbers_are_jumpers no)
		(fp_poly
			(pts
				(xy 0.2794 -0.1016) (xy -0.2794 -0.1016) (xy -0.2794 0.9906) (xy 0.2794 0.9906)
			)
			(stroke
				(width 0)
				(type default)
			)
			(fill no)
			(layer "B.CrtYd")
		)
		(fp_line
			(start -0.2794 -0.1016)
			(end 0.2794 -0.1016)
			(stroke
				(width 0.1)
				(type default)
			)
			(layer "B.Fab")
		)
		(fp_line
			(start -0.2794 0.9906)
			(end -0.2794 -0.1016)
			(stroke
				(width 0.1)
				(type default)
			)
			(layer "B.Fab")
		)
		(fp_line
			(start 0.2794 -0.1016)
			(end 0.2794 0.9906)
			(stroke
				(width 0.1)
				(type default)
			)
			(layer "B.Fab")
		)
		(fp_line
			(start 0.2794 0.9906)
			(end -0.2794 0.9906)
			(stroke
				(width 0.1)
				(type default)
			)
			(layer "B.Fab")
		)
		(pad "1" smd rect
			(at 0 0 180)
			(size 0.508 0.508)
			(layers "B.Cu" "B.Mask" "B.Paste")
			(net "RST_RSMRST_R_N")
		)
		(pad "2" smd rect
			(at 0 0.889 180)
			(size 0.508 0.508)
			(layers "B.Cu" "B.Mask" "B.Paste")
			(net "GND")
		)
		(zone
			(layer "B.Cu")
			(hatch none 0.5)
			(connect_pads
				(clearance 0)
			)
			(min_thickness 0.25)
			(keepout
				(tracks allowed)
				(vias not_allowed)
				(pads allowed)
				(copperpour not_allowed)
				(footprints allowed)
			)
			(placement
				(enabled no)
				(sheetname "")
			)
			(fill
				(thermal_gap 0.5)
				(thermal_bridge_width 0.5)
				(island_removal_mode 0)
			)
			(polygon
				(pts
					(xy 378.01042 -66.9671) (xy 377.50242 -66.9671) (xy 377.50242 -66.5861) (xy 378.01042 -66.5861)
				)
			)
		)
		(zone
			(layer "B.Cu")
			(hatch none 0.5)
			(connect_pads
				(clearance 0)
			)
			(min_thickness 0.25)
			(keepout
				(tracks not_allowed)
				(vias allowed)
				(pads allowed)
				(copperpour not_allowed)
				(footprints allowed)
			)
			(placement
				(enabled no)
				(sheetname "")
			)
			(fill
				(thermal_gap 0.5)
				(thermal_bridge_width 0.5)
				(island_removal_mode 0)
			)
			(polygon
				(pts
					(xy 378.01042 -66.5861) (xy 377.50242 -66.5861) (xy 377.50242 -66.9671) (xy 378.01042 -66.9671)
				)
			)
		)
	)
	(footprint ""
		(layer "B.Cu")
		(at 367.925604 -151.694388)
		(property "Reference" "C7W12"
			(at 0 0 0)
			(layer "B.SilkS")
			(hide yes)
			(effects
				(font
					(size 1.27 1.27)
				)
				(justify mirror)
			)
		)
		(property "Value" "*"
			(at 0.0762 -6.2357 0)
			(unlocked yes)
			(layer "B.Fab")
			(hide yes)
			(effects
				(font
					(size 1.27 1.016)
					(thickness 0.1524)
				)
				(justify mirror)
			)
		)
		(property "Device Type" "SC22U16V5MX-4-GP_SMD-BCG5-SC22A"
			(at 0.0762 -8.2677 0)
			(unlocked yes)
			(layer "B.Fab")
			(hide yes)
			(effects
				(font
					(size 1.27 1.016)
					(thickness 0.1524)
				)
				(justify mirror)
			)
		)
		(duplicate_pad_numbers_are_jumpers no)
		(fp_line
			(start -0.635 0)
			(end 0.635 0)
			(stroke
				(width 0.508)
				(type default)
			)
			(layer "B.SilkS")
		)
		(fp_rect
			(start 0.9652 1.778)
			(end -0.9652 -1.778)
			(stroke
				(width 0)
				(type default)
			)
			(fill no)
			(layer "B.CrtYd")
		)
		(fp_poly
			(pts
				(xy 0.9652 -1.778) (xy -0.9652 -1.778) (xy -0.9652 1.778) (xy 0.9652 1.778)
			)
			(stroke
				(width 0)
				(type default)
			)
			(fill no)
			(layer "B.Fab")
		)
		(pad "1" smd rect
			(at 0 -0.9652 180)
			(size 1.397 1.143)
			(layers "B.Cu" "B.Mask" "B.Paste")
			(net "VR_FET_SW_P12V_STBY_PVDDQ_DEF")
		)
		(pad "2" smd rect
			(at 0 0.9652 180)
			(size 1.397 1.143)
			(layers "B.Cu" "B.Mask" "B.Paste")
			(net "GND")
		)
	)
	(footprint ""
		(layer "B.Cu")
		(at 479.9838 -43.4086 90)
		(property "Reference" "C1R21"
			(at 0 0 90)
			(layer "B.SilkS")
			(hide yes)
			(effects
				(font
					(size 1.27 1.27)
				)
				(justify mirror)
			)
		)
		(property "Value" ""
			(at 0 0 90)
			(layer "B.Fab")
			(effects
				(font
					(size 1.27 1.27)
				)
				(justify mirror)
			)
		)
		(duplicate_pad_numbers_are_jumpers no)
		(fp_poly
			(pts
				(xy -0.3048 -0.1016) (xy -0.3048 0.9906) (xy 0.3048 0.9906) (xy 0.3048 -0.1016)
			)
			(stroke
				(width 0)
				(type default)
			)
			(fill no)
			(layer "B.CrtYd")
		)
		(fp_line
			(start 0.3048 -0.1016)
			(end 0.3048 0.9906)
			(stroke
				(width 0.1)
				(type default)
			)
			(layer "B.Fab")
		)
		(fp_line
			(start -0.3048 -0.1016)
			(end 0.3048 -0.1016)
			(stroke
				(width 0.1)
				(type default)
			)
			(layer "B.Fab")
		)
		(fp_line
			(start 0.3048 0.9906)
			(end -0.3048 0.9906)
			(stroke
				(width 0.1)
				(type default)
			)
			(layer "B.Fab")
		)
		(fp_line
			(start -0.3048 0.9906)
			(end -0.3048 -0.1016)
			(stroke
				(width 0.1)
				(type default)
			)
			(layer "B.Fab")
		)
		(pad "1" smd rect
			(at 0 0 270)
			(size 0.508 0.508)
			(layers "B.Cu" "B.Mask" "B.Paste")
			(net "P3V3_STBY")
		)
		(pad "2" smd rect
			(at 0 0.889 270)
			(size 0.508 0.508)
			(layers "B.Cu" "B.Mask" "B.Paste")
			(net "GND")
		)
		(zone
			(layer "B.Cu")
			(hatch none 0.5)
			(connect_pads
				(clearance 0)
			)
			(min_thickness 0.25)
			(keepout
				(tracks allowed)
				(vias not_allowed)
				(pads allowed)
				(copperpour not_allowed)
				(footprints allowed)
			)
			(placement
				(enabled no)
				(sheetname "")
			)
			(fill
				(thermal_gap 0.5)
				(thermal_bridge_width 0.5)
				(island_removal_mode 0)
			)
			(polygon
				(pts
					(xy 480.2378 -43.6626) (xy 480.2378 -43.1546) (xy 480.6188 -43.1546) (xy 480.6188 -43.6626)
				)
			)
		)
		(zone
			(layer "B.Cu")
			(hatch none 0.5)
			(connect_pads
				(clearance 0)
			)
			(min_thickness 0.25)
			(keepout
				(tracks not_allowed)
				(vias allowed)
				(pads allowed)
				(copperpour not_allowed)
				(footprints allowed)
			)
			(placement
				(enabled no)
				(sheetname "")
			)
			(fill
				(thermal_gap 0.5)
				(thermal_bridge_width 0.5)
				(island_removal_mode 0)
			)
			(polygon
				(pts
					(xy 480.6188 -43.6626) (xy 480.6188 -43.1546) (xy 480.2378 -43.1546) (xy 480.2378 -43.6626)
				)
			)
		)
	)
)
